(kicad_pcb
	(version 20260206)
	(generator "pcbnew")
	(generator_version "10.0")
	(general
		(thickness 1.6)
		(legacy_teardrops no)
	)
	(paper "A4")
	(title_block
		(title "Bryce Canyon_IOM_M2_16342-2_OCP.brd")
		(comment 1 "Bryce Canyon / footprints 384-390 of 1146")
	)
	(layers
		(0 "F.Cu" signal "TOP")
		(4 "In1.Cu" signal "L2GND")
		(6 "In2.Cu" signal "L3")
		(8 "In3.Cu" signal "L4VCC")
		(10 "In4.Cu" signal "L5VCC")
		(12 "In5.Cu" signal "L6")
		(14 "In6.Cu" signal "L7GND")
		(2 "B.Cu" signal "BOTTOM")
		(9 "F.Adhes" user "F.Adhesive")
		(11 "B.Adhes" user "B.Adhesive")
		(13 "F.Paste" user "Package Geometry/Pastemask Top")
		(15 "B.Paste" user "Package Geometry/Pastemask Bottom")
		(5 "F.SilkS" user "Ref Des/Silkscreen Top")
		(7 "B.SilkS" user "Ref Des/Silkscreen Bottom")
		(1 "F.Mask" user "Board Geometry/Soldermask Top")
		(3 "B.Mask" user "Board Geometry/Soldermask Bottom")
		(17 "Dwgs.User" user "User.Drawings")
		(19 "Cmts.User" user "User.Comments")
		(21 "Eco1.User" user "User.Eco1")
		(23 "Eco2.User" user "User.Eco2")
		(25 "Edge.Cuts" user "Board Geometry/Outline")
		(27 "Margin" user)
		(31 "F.CrtYd" user "Package Geometry/Place Bound Top")
		(29 "B.CrtYd" user "Package Geometry/Place Bound Bottom")
		(35 "F.Fab" user "Ref Des/Assembly Top")
		(33 "B.Fab" user "Ref Des/Assembly Bottom")
	)
	(footprint ""
		(layer "F.Cu")
		(at 57.399936 -167.828722)
		(property "Reference" "R197"
			(at 0 0 0)
			(layer "F.SilkS")
			(hide yes)
			(effects
				(font
					(size 1.27 1.27)
				)
			)
		)
		(property "Value" "2K2R2F-GP"
			(at 0.064008 -3.993896 0)
			(unlocked yes)
			(layer "F.Fab")
			(hide yes)
			(effects
				(font
					(size 1.016 1.016)
					(thickness 0.1524)
				)
			)
		)
		(property "Device Type" "R402H16"
			(at 0.064008 -5.517896 0)
			(unlocked yes)
			(layer "F.Fab")
			(hide yes)
			(effects
				(font
					(size 1.016 1.016)
					(thickness 0.1524)
				)
			)
		)
		(duplicate_pad_numbers_are_jumpers no)
		(fp_line
			(start -0.508 -0.9398)
			(end -0.508 0.9398)
			(stroke
				(width 0.1524)
				(type default)
			)
			(layer "F.SilkS")
		)
		(fp_line
			(start 0.508 -0.9398)
			(end -0.508 -0.9398)
			(stroke
				(width 0.1524)
				(type default)
			)
			(layer "F.SilkS")
		)
		(fp_rect
			(start -0.508 0.9398)
			(end 0.508 -0.9398)
			(stroke
				(width 0)
				(type default)
			)
			(fill no)
			(layer "F.CrtYd")
		)
		(fp_rect
			(start -0.508 0.9398)
			(end 0.508 -0.9398)
			(stroke
				(width 0)
				(type default)
			)
			(fill no)
			(layer "F.Fab")
		)
		(pad "1" smd custom
			(at 0 -0.4445)
			(size 0.1397 0.1397)
			(layers "F.Cu" "F.Mask" "F.Paste")
			(net "I2C_TPM_SDA")
			(options
				(clearance outline)
				(anchor circle)
			)
			(primitives
				(gr_poly
					(pts
						(arc
							(start -0.1778 -0.2794)
							(mid -0.249642 -0.249642)
							(end -0.2794 -0.1778)
						)
						(arc
							(start -0.2794 0.1778)
							(mid -0.249642 0.249642)
							(end -0.1778 0.2794)
						)
						(arc
							(start 0.1778 0.2794)
							(mid 0.249642 0.249642)
							(end 0.2794 0.1778)
						)
						(arc
							(start 0.2794 -0.1778)
							(mid 0.249642 -0.249642)
							(end 0.1778 -0.2794)
						)
					)
					(width 0)
					(fill yes)
				)
			)
		)
		(pad "2" smd custom
			(at 0 0.4445)
			(size 0.1397 0.1397)
			(layers "F.Cu" "F.Mask" "F.Paste")
			(net "P3V3_STBY")
			(options
				(clearance outline)
				(anchor circle)
			)
			(primitives
				(gr_poly
					(pts
						(arc
							(start -0.1778 -0.2794)
							(mid -0.249642 -0.249642)
							(end -0.2794 -0.1778)
						)
						(arc
							(start -0.2794 0.1778)
							(mid -0.249642 0.249642)
							(end -0.1778 0.2794)
						)
						(arc
							(start 0.1778 0.2794)
							(mid 0.249642 0.249642)
							(end 0.2794 0.1778)
						)
						(arc
							(start 0.2794 -0.1778)
							(mid 0.249642 -0.249642)
							(end 0.1778 -0.2794)
						)
					)
					(width 0)
					(fill yes)
				)
			)
		)
	)
	(footprint ""
		(layer "F.Cu")
		(at 66.276474 -175.088296)
		(property "Reference" "U10"
			(at 0 0 0)
			(layer "F.SilkS")
			(hide yes)
			(effects
				(font
					(size 1.27 1.27)
				)
			)
		)
		(property "Value" "LMV331IDCKRG4-GP"
			(at -2.3368 -8.6868 0)
			(unlocked yes)
			(layer "F.Fab")
			(hide yes)
			(effects
				(font
					(size 1.016 1.016)
					(thickness 0.1524)
				)
			)
		)
		(property "Device Type" "SC70-5H44"
			(at -2.3114 -10.414 0)
			(unlocked yes)
			(layer "F.Fab")
			(hide yes)
			(effects
				(font
					(size 1.016 1.016)
					(thickness 0.1524)
				)
			)
		)
		(duplicate_pad_numbers_are_jumpers no)
		(fp_line
			(start -1.27 -1.7018)
			(end 1.27 -1.7018)
			(stroke
				(width 0.1524)
				(type default)
			)
			(layer "F.SilkS")
		)
		(fp_line
			(start -1.27 1.7018)
			(end -1.27 -1.7018)
			(stroke
				(width 0.1524)
				(type default)
			)
			(layer "F.SilkS")
		)
		(fp_line
			(start 0.6604 -1.8034)
			(end 1.3843 -1.8034)
			(stroke
				(width 0.3302)
				(type default)
			)
			(layer "F.SilkS")
		)
		(fp_line
			(start 1.27 -1.7018)
			(end 1.27 1.7018)
			(stroke
				(width 0.1524)
				(type default)
			)
			(layer "F.SilkS")
		)
		(fp_line
			(start 1.27 1.7018)
			(end -1.27 1.7018)
			(stroke
				(width 0.1524)
				(type default)
			)
			(layer "F.SilkS")
		)
		(fp_line
			(start 1.3843 -1.8034)
			(end 1.3843 -1.1176)
			(stroke
				(width 0.3302)
				(type default)
			)
			(layer "F.SilkS")
		)
		(fp_rect
			(start -1.524 1.9558)
			(end 1.524 -1.9558)
			(stroke
				(width 0)
				(type default)
			)
			(fill no)
			(layer "F.CrtYd")
		)
		(fp_poly
			(pts
				(xy -1.524 -1.9558) (xy 1.524 -1.9558) (xy 1.524 1.9558) (xy -1.524 1.9558)
			)
			(stroke
				(width 0)
				(type default)
			)
			(fill no)
			(layer "F.Fab")
		)
		(pad "1" smd rect
			(at 0.65024 -0.8255)
			(size 0.4064 1.2192)
			(layers "F.Cu" "F.Mask" "F.Paste")
			(net "FM_TPM_PRSNT_RST_N")
		)
		(pad "2" smd rect
			(at 0 -0.8255)
			(size 0.4064 1.2192)
			(layers "F.Cu" "F.Mask" "F.Paste")
			(net "GND")
		)
		(pad "3" smd rect
			(at -0.65024 -0.8255)
			(size 0.4064 1.2192)
			(layers "F.Cu" "F.Mask" "F.Paste")
			(net "VREF_2V2")
		)
		(pad "4" smd rect
			(at -0.65024 0.8255)
			(size 0.4064 1.2192)
			(layers "F.Cu" "F.Mask" "F.Paste")
			(net "FM_TPM_PRSNT_N")
		)
		(pad "5" smd rect
			(at 0.65024 0.8255)
			(size 0.4064 1.2192)
			(layers "F.Cu" "F.Mask" "F.Paste")
			(net "P5V_STBY")
		)
	)
	(footprint ""
		(layer "F.Cu")
		(at 23.368 -130.9878 180)
		(property "Reference" "R214"
			(at 0 0 180)
			(layer "F.SilkS")
			(hide yes)
			(effects
				(font
					(size 1.27 1.27)
				)
			)
		)
		(property "Value" "2K7R2F-GP"
			(at 0.064008 -3.993896 180)
			(unlocked yes)
			(layer "F.Fab")
			(hide yes)
			(effects
				(font
					(size 1.016 1.016)
					(thickness 0.1524)
				)
			)
		)
		(property "Device Type" "R402H16"
			(at 0.064008 -5.517896 180)
			(unlocked yes)
			(layer "F.Fab")
			(hide yes)
			(effects
				(font
					(size 1.016 1.016)
					(thickness 0.1524)
				)
			)
		)
		(duplicate_pad_numbers_are_jumpers no)
		(fp_line
			(start 0.508 -0.9398)
			(end -0.508 -0.9398)
			(stroke
				(width 0.1524)
				(type default)
			)
			(layer "F.SilkS")
		)
		(fp_line
			(start -0.508 -0.9398)
			(end -0.508 0.9398)
			(stroke
				(width 0.1524)
				(type default)
			)
			(layer "F.SilkS")
		)
		(fp_rect
			(start -0.508 0.9398)
			(end 0.508 -0.9398)
			(stroke
				(width 0)
				(type default)
			)
			(fill no)
			(layer "F.CrtYd")
		)
		(fp_rect
			(start -0.508 0.9398)
			(end 0.508 -0.9398)
			(stroke
				(width 0)
				(type default)
			)
			(fill no)
			(layer "F.Fab")
		)
		(pad "1" smd custom
			(at 0 -0.4445 180)
			(size 0.1397 0.1397)
			(layers "F.Cu" "F.Mask" "F.Paste")
			(net "DDR4_ALERT")
			(options
				(clearance outline)
				(anchor circle)
			)
			(primitives
				(gr_poly
					(pts
						(arc
							(start -0.1778 -0.2794)
							(mid -0.249642 -0.249642)
							(end -0.2794 -0.1778)
						)
						(arc
							(start -0.2794 0.1778)
							(mid -0.249642 0.249642)
							(end -0.1778 0.2794)
						)
						(arc
							(start 0.1778 0.2794)
							(mid 0.249642 0.249642)
							(end 0.2794 0.1778)
						)
						(arc
							(start 0.2794 -0.1778)
							(mid 0.249642 -0.249642)
							(end 0.1778 -0.2794)
						)
					)
					(width 0)
					(fill yes)
				)
			)
		)
		(pad "2" smd custom
			(at 0 0.4445 180)
			(size 0.1397 0.1397)
			(layers "F.Cu" "F.Mask" "F.Paste")
			(net "P1V2_STBY")
			(options
				(clearance outline)
				(anchor circle)
			)
			(primitives
				(gr_poly
					(pts
						(arc
							(start -0.1778 -0.2794)
							(mid -0.249642 -0.249642)
							(end -0.2794 -0.1778)
						)
						(arc
							(start -0.2794 0.1778)
							(mid -0.249642 0.249642)
							(end -0.1778 0.2794)
						)
						(arc
							(start 0.1778 0.2794)
							(mid 0.249642 0.249642)
							(end 0.2794 0.1778)
						)
						(arc
							(start 0.2794 -0.1778)
							(mid 0.249642 -0.249642)
							(end 0.1778 -0.2794)
						)
					)
					(width 0)
					(fill yes)
				)
			)
		)
	)
	(footprint ""
		(layer "F.Cu")
		(at 201.9046 -110.7694)
		(property "Reference" "R548"
			(at 0 0 0)
			(layer "F.SilkS")
			(hide yes)
			(effects
				(font
					(size 1.27 1.27)
				)
			)
		)
		(property "Value" "4K7R2F-GP"
			(at 0.064008 -3.993896 0)
			(unlocked yes)
			(layer "F.Fab")
			(hide yes)
			(effects
				(font
					(size 1.016 1.016)
					(thickness 0.1524)
				)
			)
		)
		(property "Device Type" "R402H16"
			(at 0.064008 -5.517896 0)
			(unlocked yes)
			(layer "F.Fab")
			(hide yes)
			(effects
				(font
					(size 1.016 1.016)
					(thickness 0.1524)
				)
			)
		)
		(duplicate_pad_numbers_are_jumpers no)
		(fp_line
			(start -0.508 -0.9398)
			(end -0.508 0.9398)
			(stroke
				(width 0.1524)
				(type default)
			)
			(layer "F.SilkS")
		)
		(fp_line
			(start 0.508 -0.9398)
			(end -0.508 -0.9398)
			(stroke
				(width 0.1524)
				(type default)
			)
			(layer "F.SilkS")
		)
		(fp_rect
			(start -0.508 0.9398)
			(end 0.508 -0.9398)
			(stroke
				(width 0)
				(type default)
			)
			(fill no)
			(layer "F.CrtYd")
		)
		(fp_rect
			(start -0.508 0.9398)
			(end 0.508 -0.9398)
			(stroke
				(width 0)
				(type default)
			)
			(fill no)
			(layer "F.Fab")
		)
		(pad "1" smd custom
			(at 0 -0.4445)
			(size 0.1397 0.1397)
			(layers "F.Cu" "F.Mask" "F.Paste")
			(net "P3V3_STBY")
			(options
				(clearance outline)
				(anchor circle)
			)
			(primitives
				(gr_poly
					(pts
						(arc
							(start -0.1778 -0.2794)
							(mid -0.249642 -0.249642)
							(end -0.2794 -0.1778)
						)
						(arc
							(start -0.2794 0.1778)
							(mid -0.249642 0.249642)
							(end -0.1778 0.2794)
						)
						(arc
							(start 0.1778 0.2794)
							(mid 0.249642 0.249642)
							(end 0.2794 0.1778)
						)
						(arc
							(start 0.2794 -0.1778)
							(mid 0.249642 -0.249642)
							(end 0.1778 -0.2794)
						)
					)
					(width 0)
					(fill yes)
				)
			)
		)
		(pad "2" smd custom
			(at 0 0.4445)
			(size 0.1397 0.1397)
			(layers "F.Cu" "F.Mask" "F.Paste")
			(net "TEMP_2_A0")
			(options
				(clearance outline)
				(anchor circle)
			)
			(primitives
				(gr_poly
					(pts
						(arc
							(start -0.1778 -0.2794)
							(mid -0.249642 -0.249642)
							(end -0.2794 -0.1778)
						)
						(arc
							(start -0.2794 0.1778)
							(mid -0.249642 0.249642)
							(end -0.1778 0.2794)
						)
						(arc
							(start 0.1778 0.2794)
							(mid 0.249642 0.249642)
							(end 0.2794 0.1778)
						)
						(arc
							(start 0.2794 -0.1778)
							(mid 0.249642 -0.249642)
							(end 0.1778 -0.2794)
						)
					)
					(width 0)
					(fill yes)
				)
			)
		)
	)
	(footprint ""
		(layer "F.Cu")
		(at 45.913802 -116.78412 -90)
		(property "Reference" "R86"
			(at 0 0 270)
			(layer "F.SilkS")
			(hide yes)
			(effects
				(font
					(size 1.27 1.27)
				)
			)
		)
		(property "Value" "2K2R2J-2-GP"
			(at 0.064008 -3.993896 270)
			(unlocked yes)
			(layer "F.Fab")
			(hide yes)
			(effects
				(font
					(size 1.016 1.016)
					(thickness 0.1524)
				)
			)
		)
		(property "Device Type" "R402H16"
			(at 0.064008 -5.517896 270)
			(unlocked yes)
			(layer "F.Fab")
			(hide yes)
			(effects
				(font
					(size 1.016 1.016)
					(thickness 0.1524)
				)
			)
		)
		(duplicate_pad_numbers_are_jumpers no)
		(fp_line
			(start -0.508 -0.9398)
			(end -0.508 0.9398)
			(stroke
				(width 0.1524)
				(type default)
			)
			(layer "F.SilkS")
		)
		(fp_line
			(start 0.508 -0.9398)
			(end -0.508 -0.9398)
			(stroke
				(width 0.1524)
				(type default)
			)
			(layer "F.SilkS")
		)
		(fp_rect
			(start -0.508 0.9398)
			(end 0.508 -0.9398)
			(stroke
				(width 0)
				(type default)
			)
			(fill no)
			(layer "F.CrtYd")
		)
		(fp_rect
			(start -0.508 0.9398)
			(end 0.508 -0.9398)
			(stroke
				(width 0)
				(type default)
			)
			(fill no)
			(layer "F.Fab")
		)
		(pad "1" smd custom
			(at 0 -0.4445 270)
			(size 0.1397 0.1397)
			(layers "F.Cu" "F.Mask" "F.Paste")
			(net "P3V3_STBY")
			(options
				(clearance outline)
				(anchor circle)
			)
			(primitives
				(gr_poly
					(pts
						(arc
							(start -0.1778 -0.2794)
							(mid -0.249642 -0.249642)
							(end -0.2794 -0.1778)
						)
						(arc
							(start -0.2794 0.1778)
							(mid -0.249642 0.249642)
							(end -0.1778 0.2794)
						)
						(arc
							(start 0.1778 0.2794)
							(mid 0.249642 0.249642)
							(end 0.2794 0.1778)
						)
						(arc
							(start 0.2794 -0.1778)
							(mid 0.249642 -0.249642)
							(end 0.1778 -0.2794)
						)
					)
					(width 0)
					(fill yes)
				)
			)
		)
		(pad "2" smd custom
			(at 0 0.4445 270)
			(size 0.1397 0.1397)
			(layers "F.Cu" "F.Mask" "F.Paste")
			(net "FLA0_SPI_HOLD_N")
			(options
				(clearance outline)
				(anchor circle)
			)
			(primitives
				(gr_poly
					(pts
						(arc
							(start -0.1778 -0.2794)
							(mid -0.249642 -0.249642)
							(end -0.2794 -0.1778)
						)
						(arc
							(start -0.2794 0.1778)
							(mid -0.249642 0.249642)
							(end -0.1778 0.2794)
						)
						(arc
							(start 0.1778 0.2794)
							(mid 0.249642 0.249642)
							(end 0.2794 0.1778)
						)
						(arc
							(start 0.2794 -0.1778)
							(mid 0.249642 -0.249642)
							(end 0.1778 -0.2794)
						)
					)
					(width 0)
					(fill yes)
				)
			)
		)
	)
	(footprint ""
		(layer "F.Cu")
		(at 19.144742 -129.077466 180)
		(property "Reference" "R215"
			(at 0 0 180)
			(layer "F.SilkS")
			(hide yes)
			(effects
				(font
					(size 1.27 1.27)
				)
			)
		)
		(property "Value" "120R2F-GP"
			(at 0.064008 -3.993896 180)
			(unlocked yes)
			(layer "F.Fab")
			(hide yes)
			(effects
				(font
					(size 1.016 1.016)
					(thickness 0.1524)
				)
			)
		)
		(property "Device Type" "R402H16"
			(at 0.064008 -5.517896 180)
			(unlocked yes)
			(layer "F.Fab")
			(hide yes)
			(effects
				(font
					(size 1.016 1.016)
					(thickness 0.1524)
				)
			)
		)
		(duplicate_pad_numbers_are_jumpers no)
		(fp_line
			(start 0.508 -0.9398)
			(end -0.508 -0.9398)
			(stroke
				(width 0.1524)
				(type default)
			)
			(layer "F.SilkS")
		)
		(fp_line
			(start -0.508 -0.9398)
			(end -0.508 0.9398)
			(stroke
				(width 0.1524)
				(type default)
			)
			(layer "F.SilkS")
		)
		(fp_rect
			(start -0.508 0.9398)
			(end 0.508 -0.9398)
			(stroke
				(width 0)
				(type default)
			)
			(fill no)
			(layer "F.CrtYd")
		)
		(fp_rect
			(start -0.508 0.9398)
			(end 0.508 -0.9398)
			(stroke
				(width 0)
				(type default)
			)
			(fill no)
			(layer "F.Fab")
		)
		(pad "1" smd custom
			(at 0 -0.4445 180)
			(size 0.1397 0.1397)
			(layers "F.Cu" "F.Mask" "F.Paste")
			(net "GND")
			(options
				(clearance outline)
				(anchor circle)
			)
			(primitives
				(gr_poly
					(pts
						(arc
							(start -0.1778 -0.2794)
							(mid -0.249642 -0.249642)
							(end -0.2794 -0.1778)
						)
						(arc
							(start -0.2794 0.1778)
							(mid -0.249642 0.249642)
							(end -0.1778 0.2794)
						)
						(arc
							(start 0.1778 0.2794)
							(mid 0.249642 0.249642)
							(end 0.2794 0.1778)
						)
						(arc
							(start 0.2794 -0.1778)
							(mid 0.249642 -0.249642)
							(end 0.1778 -0.2794)
						)
					)
					(width 0)
					(fill yes)
				)
			)
		)
		(pad "2" smd custom
			(at 0 0.4445 180)
			(size 0.1397 0.1397)
			(layers "F.Cu" "F.Mask" "F.Paste")
			(net "MEMCSN")
			(options
				(clearance outline)
				(anchor circle)
			)
			(primitives
				(gr_poly
					(pts
						(arc
							(start -0.1778 -0.2794)
							(mid -0.249642 -0.249642)
							(end -0.2794 -0.1778)
						)
						(arc
							(start -0.2794 0.1778)
							(mid -0.249642 0.249642)
							(end -0.1778 0.2794)
						)
						(arc
							(start 0.1778 0.2794)
							(mid 0.249642 0.249642)
							(end 0.2794 0.1778)
						)
						(arc
							(start 0.2794 -0.1778)
							(mid 0.249642 -0.249642)
							(end 0.1778 -0.2794)
						)
					)
					(width 0)
					(fill yes)
				)
			)
		)
	)
	(footprint ""
		(layer "F.Cu")
		(at 67.4878 -140.4874 90)
		(property "Reference" "R56"
			(at 0 0 90)
			(layer "F.SilkS")
			(hide yes)
			(effects
				(font
					(size 1.27 1.27)
				)
			)
		)
		(property "Value" "10KR2F-2-GP"
			(at 0.064008 -3.993896 90)
			(unlocked yes)
			(layer "F.Fab")
			(hide yes)
			(effects
				(font
					(size 1.016 1.016)
					(thickness 0.1524)
				)
			)
		)
		(property "Device Type" "R402H16"
			(at 0.064008 -5.517896 90)
			(unlocked yes)
			(layer "F.Fab")
			(hide yes)
			(effects
				(font
					(size 1.016 1.016)
					(thickness 0.1524)
				)
			)
		)
		(duplicate_pad_numbers_are_jumpers no)
		(fp_line
			(start 0.508 -0.9398)
			(end -0.508 -0.9398)
			(stroke
				(width 0.1524)
				(type default)
			)
			(layer "F.SilkS")
		)
		(fp_line
			(start -0.508 -0.9398)
			(end -0.508 0.9398)
			(stroke
				(width 0.1524)
				(type default)
			)
			(layer "F.SilkS")
		)
		(fp_rect
			(start -0.508 0.9398)
			(end 0.508 -0.9398)
			(stroke
				(width 0)
				(type default)
			)
			(fill no)
			(layer "F.CrtYd")
		)
		(fp_rect
			(start -0.508 0.9398)
			(end 0.508 -0.9398)
			(stroke
				(width 0)
				(type default)
			)
			(fill no)
			(layer "F.Fab")
		)
		(pad "1" smd custom
			(at 0 -0.4445 90)
			(size 0.1397 0.1397)
			(layers "F.Cu" "F.Mask" "F.Paste")
			(net "P3V3_STBY")
			(options
				(clearance outline)
				(anchor circle)
			)
			(primitives
				(gr_poly
					(pts
						(arc
							(start -0.1778 -0.2794)
							(mid -0.249642 -0.249642)
							(end -0.2794 -0.1778)
						)
						(arc
							(start -0.2794 0.1778)
							(mid -0.249642 0.249642)
							(end -0.1778 0.2794)
						)
						(arc
							(start 0.1778 0.2794)
							(mid 0.249642 0.249642)
							(end 0.2794 0.1778)
						)
						(arc
							(start 0.2794 -0.1778)
							(mid 0.249642 -0.249642)
							(end 0.1778 -0.2794)
						)
					)
					(width 0)
					(fill yes)
				)
			)
		)
		(pad "2" smd custom
			(at 0 0.4445 90)
			(size 0.1397 0.1397)
			(layers "F.Cu" "F.Mask" "F.Paste")
			(net "FP_RETBTN")
			(options
				(clearance outline)
				(anchor circle)
			)
			(primitives
				(gr_poly
					(pts
						(arc
							(start -0.1778 -0.2794)
							(mid -0.249642 -0.249642)
							(end -0.2794 -0.1778)
						)
						(arc
							(start -0.2794 0.1778)
							(mid -0.249642 0.249642)
							(end -0.1778 0.2794)
						)
						(arc
							(start 0.1778 0.2794)
							(mid 0.249642 0.249642)
							(end 0.2794 0.1778)
						)
						(arc
							(start 0.2794 -0.1778)
							(mid 0.249642 -0.249642)
							(end 0.1778 -0.2794)
						)
					)
					(width 0)
					(fill yes)
				)
			)
		)
	)
)
